FILE_TYPE = CONNECTIVITY;
{Allegro Design Entry HDL 16.6-p007 (v16-6-112F) 10/10/2012}
"PAGE_NUMBER" = 27;
0"NC";
1"M_E_DQS_DP<17:0>";
2"M_E_DQS_DN<17:0>";
3"M_E_MA<17:0>";
4"M_E_BA<1:0>";
5"M_E_BG<1:0>";
6"M_E_CKE<3:0>";
7"M_E_CS_N<7:0>";
8"M_E_ODT<3:0>";
9"M_E_DQ<63:0>";
10"M_E_CLK_DN<3:0>";
11"M_E_CLK_DP<3:0>";
12"M_E_ECC<7:0>";
13"M_E_DQ<55>";
14"M_E_DQ<41>";
15"M_E_DQS_DP<2>";
16"M_E_DQ<53>";
17"M_E_ODT<3>";
18"M_E_DQ<35>";
19"M_E_DQ<33>";
20"M_E_DQ<38>";
21"M_E_DQ<58>";
22"M_E_DQ<5>";
23"M_E_C<2>";
24"M_E_ECC<0>";
25"M_E_ECC<1>";
26"M_E_ECC<2>";
27"M_E_ECC<3>";
28"M_E_ECC<4>";
29"M_E_ECC<5>";
30"M_E_ECC<6>";
31"M_E_ECC<7>";
32"M_E_DQ<0>";
33"M_E_DQ<1>";
34"M_E_DQ<2>";
35"M_E_DQ<3>";
36"M_E_DQ<4>";
37"M_E_DQ<6>";
38"M_E_DQ<7>";
39"M_E_DQ<8>";
40"M_E_DQ<9>";
41"M_E_DQ<10>";
42"M_E_CLK_DP<0>";
43"M_E_CLK_DP<1>";
44"M_E_CLK_DP<2>";
45"M_E_CLK_DP<3>";
46"M_E_CLK_DN<0>";
47"M_E_CLK_DN<1>";
48"M_E_CLK_DN<2>";
49"M_E_CLK_DN<3>";
50"M_E_DQ<11>";
51"M_E_DQ<12>";
52"M_E_DQ<13>";
53"M_E_DQ<14>";
54"M_E_DQ<15>";
55"M_E_DQ<16>";
56"M_E_DQ<17>";
57"M_E_DQ<18>";
58"M_E_DQ<19>";
59"M_E_DQ<20>";
60"M_E_DQ<21>";
61"M_E_DQ<22>";
62"M_E_DQ<23>";
63"M_E_DQ<24>";
64"M_E_DQ<25>";
65"M_E_DQ<26>";
66"M_E_DQ<27>";
67"M_E_DQ<28>";
68"M_E_DQ<29>";
69"M_E_DQ<30>";
70"M_E_DQ<31>";
71"M_E_DQ<32>";
72"M_E_DQ<34>";
73"M_E_DQ<36>";
74"M_E_DQ<37>";
75"M_E_DQ<39>";
76"M_E_DQ<40>";
77"M_E_DQ<42>";
78"M_E_DQ<43>";
79"M_E_DQ<44>";
80"M_E_DQ<45>";
81"M_E_DQ<46>";
82"M_E_DQ<47>";
83"M_E_DQ<48>";
84"M_E_DQ<49>";
85"M_E_DQ<50>";
86"M_E_DQ<51>";
87"M_E_DQ<52>";
88"M_E_DQ<54>";
89"M_E_DQ<56>";
90"M_E_DQ<57>";
91"M_E_DQ<59>";
92"M_E_DQ<60>";
93"M_E_DQ<61>";
94"M_E_DQ<62>";
95"M_E_DQ<63>";
96"M_E_ODT<0>";
97"M_E_ODT<1>";
98"M_E_ODT<2>";
99"M_E_MA<0>";
100"M_E_MA<1>";
101"M_E_MA<2>";
102"M_E_CS_N<0>";
103"M_E_CS_N<1>";
104"M_E_CS_N<2>";
105"M_E_CS_N<3>";
106"M_E_CS_N<4>";
107"M_E_CS_N<5>";
108"M_E_CS_N<6>";
109"M_E_CS_N<7>";
110"M_E_CKE<0>";
111"M_E_CKE<1>";
112"M_E_CKE<2>";
113"M_E_CKE<3>";
114"M_E_BG<0>";
115"M_E_BG<1>";
116"M_E_BA<0>";
117"M_E_BA<1>";
118"M_E_ALERT_N";
119"M_E_PAR";
120"M_E_ACT_N";
121"M_E_MA<3>";
122"M_E_MA<4>";
123"M_E_MA<5>";
124"M_E_MA<6>";
125"M_E_MA<7>";
126"M_E_MA<8>";
127"M_E_MA<9>";
128"M_E_MA<10>";
129"M_E_MA<11>";
130"M_E_MA<12>";
131"M_E_MA<13>";
132"M_E_MA<14>";
133"M_E_MA<15>";
134"M_E_MA<16>";
135"M_E_MA<17>";
136"M_E_DQS_DP<0>";
137"M_E_DQS_DP<1>";
138"M_E_DQS_DP<3>";
139"M_E_DQS_DP<4>";
140"M_E_DQS_DP<5>";
141"M_E_DQS_DN<0>";
142"M_E_DQS_DN<1>";
143"M_E_DQS_DN<2>";
144"M_E_DQS_DN<3>";
145"M_E_DQS_DN<4>";
146"M_E_DQS_DN<5>";
147"M_E_DQS_DN<6>";
148"M_E_DQS_DN<7>";
149"M_E_DQS_DN<8>";
150"M_E_DQS_DN<9>";
151"M_E_DQS_DN<10>";
152"M_E_DQS_DN<11>";
153"M_E_DQS_DN<12>";
154"M_E_DQS_DN<13>";
155"M_E_DQS_DN<14>";
156"M_E_DQS_DN<15>";
157"M_E_DQS_DN<16>";
158"M_E_DQS_DN<17>";
159"M_E_DQS_DP<6>";
160"M_E_DQS_DP<7>";
161"M_E_DQS_DP<8>";
162"M_E_DQS_DP<9>";
163"M_E_DQS_DP<10>";
164"M_E_DQS_DP<11>";
165"M_E_DQS_DP<12>";
166"M_E_DQS_DP<13>";
167"M_E_DQS_DP<14>";
168"M_E_DQS_DP<15>";
169"M_E_DQS_DP<16>";
170"M_E_DQS_DP<17>";
%"TAP"
"6","(-5575,850)","0","mstr_standard","I10";
;
CDS_LIB"mstr_standard"
BODY_TYPE"PLUMBING"
HDL_TAP"TRUE";
"B \NAC \NWC"11;
"S \NAC"
BN"1"43;
%"TAP"
"6","(-2850,1400)","2","mstr_standard","I100";
;
CDS_LIB"mstr_standard"
BODY_TYPE"PLUMBING"
HDL_TAP"TRUE";
"B \NAC \NWC"8;
"S \NAC"
BN"0"96;
%"TAP"
"6","(-2850,1550)","2","mstr_standard","I101";
;
CDS_LIB"mstr_standard"
BODY_TYPE"PLUMBING"
HDL_TAP"TRUE";
"B \NAC \NWC"8;
"S \NAC"
BN"3"17;
%"TAP"
"6","(-2850,1500)","2","mstr_standard","I102";
;
CDS_LIB"mstr_standard"
BODY_TYPE"PLUMBING"
HDL_TAP"TRUE";
"B \NAC \NWC"8;
"S \NAC"
BN"2"98;
%"TAP"
"6","(-2850,1650)","2","mstr_standard","I103";
;
CDS_LIB"mstr_standard"
BODY_TYPE"PLUMBING"
HDL_TAP"TRUE";
"B \NAC \NWC"6;
"S \NAC"
BN"0"110;
%"TAP"
"6","(-2850,1700)","2","mstr_standard","I104";
;
CDS_LIB"mstr_standard"
BODY_TYPE"PLUMBING"
HDL_TAP"TRUE";
"B \NAC \NWC"6;
"S \NAC"
BN"1"111;
%"TAP"
"6","(-2850,1800)","2","mstr_standard","I105";
;
CDS_LIB"mstr_standard"
BODY_TYPE"PLUMBING"
HDL_TAP"TRUE";
"B \NAC \NWC"6;
"S \NAC"
BN"3"113;
%"TAP"
"6","(-2850,1750)","2","mstr_standard","I106";
;
CDS_LIB"mstr_standard"
BODY_TYPE"PLUMBING"
HDL_TAP"TRUE";
"B \NAC \NWC"6;
"S \NAC"
BN"2"112;
%"TAP"
"6","(-2850,1900)","2","mstr_standard","I107";
;
CDS_LIB"mstr_standard"
BODY_TYPE"PLUMBING"
HDL_TAP"TRUE";
"B \NAC \NWC"3;
"S \NAC"
BN"0"99;
%"TAP"
"6","(-2850,1950)","2","mstr_standard","I108";
;
CDS_LIB"mstr_standard"
BODY_TYPE"PLUMBING"
HDL_TAP"TRUE";
"B \NAC \NWC"3;
"S \NAC"
BN"1"100;
%"TAP"
"6","(-2850,2050)","2","mstr_standard","I109";
;
CDS_LIB"mstr_standard"
BODY_TYPE"PLUMBING"
HDL_TAP"TRUE";
"B \NAC \NWC"3;
"S \NAC"
BN"3"121;
%"TAP"
"6","(-5575,900)","0","mstr_standard","I11";
;
CDS_LIB"mstr_standard"
BODY_TYPE"PLUMBING"
HDL_TAP"TRUE";
"B \NAC \NWC"11;
"S \NAC"
BN"2"44;
%"TAP"
"6","(-2850,2000)","2","mstr_standard","I110";
;
CDS_LIB"mstr_standard"
BODY_TYPE"PLUMBING"
HDL_TAP"TRUE";
"B \NAC \NWC"3;
"S \NAC"
BN"2"101;
%"TAP"
"6","(-2850,2100)","2","mstr_standard","I111";
;
CDS_LIB"mstr_standard"
BODY_TYPE"PLUMBING"
HDL_TAP"TRUE";
"B \NAC \NWC"3;
"S \NAC"
BN"4"122;
%"TAP"
"6","(-2850,2150)","2","mstr_standard","I112";
;
CDS_LIB"mstr_standard"
BODY_TYPE"PLUMBING"
HDL_TAP"TRUE";
"B \NAC \NWC"3;
"S \NAC"
BN"5"123;
%"TAP"
"6","(-2850,2200)","2","mstr_standard","I113";
;
CDS_LIB"mstr_standard"
BODY_TYPE"PLUMBING"
HDL_TAP"TRUE";
"B \NAC \NWC"3;
"S \NAC"
BN"6"124;
%"TAP"
"6","(-2850,2350)","2","mstr_standard","I114";
;
CDS_LIB"mstr_standard"
BODY_TYPE"PLUMBING"
HDL_TAP"TRUE";
"B \NAC \NWC"3;
"S \NAC"
BN"9"127;
%"TAP"
"6","(-2850,2300)","2","mstr_standard","I115";
;
CDS_LIB"mstr_standard"
BODY_TYPE"PLUMBING"
HDL_TAP"TRUE";
"B \NAC \NWC"3;
"S \NAC"
BN"8"126;
%"TAP"
"6","(-2850,2250)","2","mstr_standard","I116";
;
CDS_LIB"mstr_standard"
BODY_TYPE"PLUMBING"
HDL_TAP"TRUE";
"B \NAC \NWC"3;
"S \NAC"
BN"7"125;
%"TAP"
"6","(-2850,2450)","2","mstr_standard","I117";
;
CDS_LIB"mstr_standard"
BODY_TYPE"PLUMBING"
HDL_TAP"TRUE";
"B \NAC \NWC"3;
"S \NAC"
BN"11"129;
%"TAP"
"6","(-2850,2400)","2","mstr_standard","I118";
;
CDS_LIB"mstr_standard"
BODY_TYPE"PLUMBING"
HDL_TAP"TRUE";
"B \NAC \NWC"3;
"S \NAC"
BN"10"128;
%"TAP"
"6","(-2850,2500)","2","mstr_standard","I119";
;
CDS_LIB"mstr_standard"
BODY_TYPE"PLUMBING"
HDL_TAP"TRUE";
"B \NAC \NWC"3;
"S \NAC"
BN"12"130;
%"TAP"
"6","(-5575,950)","0","mstr_standard","I12";
;
CDS_LIB"mstr_standard"
BODY_TYPE"PLUMBING"
HDL_TAP"TRUE";
"B \NAC \NWC"11;
"S \NAC"
BN"3"45;
%"TAP"
"6","(-2850,2550)","2","mstr_standard","I120";
;
CDS_LIB"mstr_standard"
BODY_TYPE"PLUMBING"
HDL_TAP"TRUE";
"B \NAC \NWC"3;
"S \NAC"
BN"13"131;
%"TAP"
"6","(-2850,2600)","2","mstr_standard","I121";
;
CDS_LIB"mstr_standard"
BODY_TYPE"PLUMBING"
HDL_TAP"TRUE";
"B \NAC \NWC"3;
"S \NAC"
BN"14"132;
%"TAP"
"6","(-2850,2700)","2","mstr_standard","I122";
;
CDS_LIB"mstr_standard"
BODY_TYPE"PLUMBING"
HDL_TAP"TRUE";
"B \NAC \NWC"3;
"S \NAC"
BN"16"134;
%"TAP"
"6","(-2850,2650)","2","mstr_standard","I123";
;
CDS_LIB"mstr_standard"
BODY_TYPE"PLUMBING"
HDL_TAP"TRUE";
"B \NAC \NWC"3;
"S \NAC"
BN"15"133;
%"TAP"
"6","(-2850,2750)","2","mstr_standard","I124";
;
CDS_LIB"mstr_standard"
BODY_TYPE"PLUMBING"
HDL_TAP"TRUE";
"B \NAC \NWC"3;
"S \NAC"
BN"17"135;
%"TAP"
"6","(-2850,2850)","2","mstr_standard","I125";
;
CDS_LIB"mstr_standard"
BODY_TYPE"PLUMBING"
HDL_TAP"TRUE";
"B \NAC \NWC"2;
"S \NAC"
BN"0"141;
%"TAP"
"6","(-2850,2950)","2","mstr_standard","I126";
;
CDS_LIB"mstr_standard"
BODY_TYPE"PLUMBING"
HDL_TAP"TRUE";
"B \NAC \NWC"2;
"S \NAC"
BN"2"143;
%"TAP"
"6","(-2850,2900)","2","mstr_standard","I127";
;
CDS_LIB"mstr_standard"
BODY_TYPE"PLUMBING"
HDL_TAP"TRUE";
"B \NAC \NWC"2;
"S \NAC"
BN"1"142;
%"TAP"
"6","(-2850,3000)","2","mstr_standard","I128";
;
CDS_LIB"mstr_standard"
BODY_TYPE"PLUMBING"
HDL_TAP"TRUE";
"B \NAC \NWC"2;
"S \NAC"
BN"3"144;
%"TAP"
"6","(-2850,3050)","2","mstr_standard","I129";
;
CDS_LIB"mstr_standard"
BODY_TYPE"PLUMBING"
HDL_TAP"TRUE";
"B \NAC \NWC"2;
"S \NAC"
BN"4"145;
%"TAP"
"6","(-5575,1050)","0","mstr_standard","I13";
;
CDS_LIB"mstr_standard"
BODY_TYPE"PLUMBING"
HDL_TAP"TRUE";
"B \NAC \NWC"12;
"S \NAC"
BN"0"24;
%"TAP"
"6","(-2850,3100)","2","mstr_standard","I130";
;
CDS_LIB"mstr_standard"
BODY_TYPE"PLUMBING"
HDL_TAP"TRUE";
"B \NAC \NWC"2;
"S \NAC"
BN"5"146;
%"TAP"
"6","(-2850,3200)","2","mstr_standard","I131";
;
CDS_LIB"mstr_standard"
BODY_TYPE"PLUMBING"
HDL_TAP"TRUE";
"B \NAC \NWC"2;
"S \NAC"
BN"7"148;
%"TAP"
"6","(-2850,3150)","2","mstr_standard","I132";
;
CDS_LIB"mstr_standard"
BODY_TYPE"PLUMBING"
HDL_TAP"TRUE";
"B \NAC \NWC"2;
"S \NAC"
BN"6"147;
%"TAP"
"6","(-2850,3250)","2","mstr_standard","I133";
;
CDS_LIB"mstr_standard"
BODY_TYPE"PLUMBING"
HDL_TAP"TRUE";
"B \NAC \NWC"2;
"S \NAC"
BN"8"149;
%"TAP"
"6","(-2850,3350)","2","mstr_standard","I134";
;
CDS_LIB"mstr_standard"
BODY_TYPE"PLUMBING"
HDL_TAP"TRUE";
"B \NAC \NWC"2;
"S \NAC"
BN"10"151;
%"TAP"
"6","(-2850,3300)","2","mstr_standard","I135";
;
CDS_LIB"mstr_standard"
BODY_TYPE"PLUMBING"
HDL_TAP"TRUE";
"B \NAC \NWC"2;
"S \NAC"
BN"9"150;
%"TAP"
"6","(-2850,3500)","2","mstr_standard","I136";
;
CDS_LIB"mstr_standard"
BODY_TYPE"PLUMBING"
HDL_TAP"TRUE";
"B \NAC \NWC"2;
"S \NAC"
BN"13"154;
%"TAP"
"6","(-2850,3400)","2","mstr_standard","I137";
;
CDS_LIB"mstr_standard"
BODY_TYPE"PLUMBING"
HDL_TAP"TRUE";
"B \NAC \NWC"2;
"S \NAC"
BN"11"152;
%"TAP"
"6","(-2850,3450)","2","mstr_standard","I138";
;
CDS_LIB"mstr_standard"
BODY_TYPE"PLUMBING"
HDL_TAP"TRUE";
"B \NAC \NWC"2;
"S \NAC"
BN"12"153;
%"TAP"
"6","(-2850,3600)","2","mstr_standard","I139";
;
CDS_LIB"mstr_standard"
BODY_TYPE"PLUMBING"
HDL_TAP"TRUE";
"B \NAC \NWC"2;
"S \NAC"
BN"15"156;
%"TAP"
"6","(-5575,1100)","0","mstr_standard","I14";
;
CDS_LIB"mstr_standard"
BODY_TYPE"PLUMBING"
HDL_TAP"TRUE";
"B \NAC \NWC"12;
"S \NAC"
BN"1"25;
%"TAP"
"6","(-2850,3550)","2","mstr_standard","I140";
;
CDS_LIB"mstr_standard"
BODY_TYPE"PLUMBING"
HDL_TAP"TRUE";
"B \NAC \NWC"2;
"S \NAC"
BN"14"155;
%"TAP"
"6","(-2850,3700)","2","mstr_standard","I141";
;
CDS_LIB"mstr_standard"
BODY_TYPE"PLUMBING"
HDL_TAP"TRUE";
"B \NAC \NWC"2;
"S \NAC"
BN"17"158;
%"TAP"
"6","(-2850,3650)","2","mstr_standard","I142";
;
CDS_LIB"mstr_standard"
BODY_TYPE"PLUMBING"
HDL_TAP"TRUE";
"B \NAC \NWC"2;
"S \NAC"
BN"16"157;
%"TAP"
"6","(-2850,3850)","2","mstr_standard","I143";
;
CDS_LIB"mstr_standard"
BODY_TYPE"PLUMBING"
HDL_TAP"TRUE";
"B \NAC \NWC"1;
"S \NAC"
BN"1"137;
%"TAP"
"6","(-2850,3800)","2","mstr_standard","I144";
;
CDS_LIB"mstr_standard"
BODY_TYPE"PLUMBING"
HDL_TAP"TRUE";
"B \NAC \NWC"1;
"S \NAC"
BN"0"136;
%"TAP"
"6","(-2850,4000)","2","mstr_standard","I145";
;
CDS_LIB"mstr_standard"
BODY_TYPE"PLUMBING"
HDL_TAP"TRUE";
"B \NAC \NWC"1;
"S \NAC"
BN"4"139;
%"TAP"
"6","(-2850,3950)","2","mstr_standard","I146";
;
CDS_LIB"mstr_standard"
BODY_TYPE"PLUMBING"
HDL_TAP"TRUE";
"B \NAC \NWC"1;
"S \NAC"
BN"3"138;
%"TAP"
"6","(-2850,3900)","2","mstr_standard","I147";
;
CDS_LIB"mstr_standard"
BODY_TYPE"PLUMBING"
HDL_TAP"TRUE";
"B \NAC \NWC"1;
"S \NAC"
BN"2"15;
%"TAP"
"6","(-5575,1150)","0","mstr_standard","I15";
;
CDS_LIB"mstr_standard"
BODY_TYPE"PLUMBING"
HDL_TAP"TRUE";
"B \NAC \NWC"12;
"S \NAC"
BN"2"26;
%"TAP"
"6","(-2850,4100)","2","mstr_standard","I158";
;
CDS_LIB"mstr_standard"
BODY_TYPE"PLUMBING"
HDL_TAP"TRUE";
"B \NAC \NWC"1;
"S \NAC"
BN"6"159;
%"TAP"
"6","(-2850,4050)","2","mstr_standard","I159";
;
CDS_LIB"mstr_standard"
BODY_TYPE"PLUMBING"
HDL_TAP"TRUE";
"B \NAC \NWC"1;
"S \NAC"
BN"5"140;
%"TAP"
"6","(-5575,1200)","0","mstr_standard","I16";
;
CDS_LIB"mstr_standard"
BODY_TYPE"PLUMBING"
HDL_TAP"TRUE";
"B \NAC \NWC"12;
"S \NAC"
BN"3"27;
%"TAP"
"6","(-2850,4150)","2","mstr_standard","I160";
;
CDS_LIB"mstr_standard"
BODY_TYPE"PLUMBING"
HDL_TAP"TRUE";
"B \NAC \NWC"1;
"S \NAC"
BN"7"160;
%"TAP"
"6","(-2850,4250)","2","mstr_standard","I161";
;
CDS_LIB"mstr_standard"
BODY_TYPE"PLUMBING"
HDL_TAP"TRUE";
"B \NAC \NWC"1;
"S \NAC"
BN"9"162;
%"TAP"
"6","(-2850,4200)","2","mstr_standard","I162";
;
CDS_LIB"mstr_standard"
BODY_TYPE"PLUMBING"
HDL_TAP"TRUE";
"B \NAC \NWC"1;
"S \NAC"
BN"8"161;
%"TAP"
"6","(-2850,4400)","2","mstr_standard","I163";
;
CDS_LIB"mstr_standard"
BODY_TYPE"PLUMBING"
HDL_TAP"TRUE";
"B \NAC \NWC"1;
"S \NAC"
BN"12"165;
%"TAP"
"6","(-2850,4350)","2","mstr_standard","I164";
;
CDS_LIB"mstr_standard"
BODY_TYPE"PLUMBING"
HDL_TAP"TRUE";
"B \NAC \NWC"1;
"S \NAC"
BN"11"164;
%"TAP"
"6","(-2850,4300)","2","mstr_standard","I165";
;
CDS_LIB"mstr_standard"
BODY_TYPE"PLUMBING"
HDL_TAP"TRUE";
"B \NAC \NWC"1;
"S \NAC"
BN"10"163;
%"TAP"
"6","(-2850,4450)","2","mstr_standard","I166";
;
CDS_LIB"mstr_standard"
BODY_TYPE"PLUMBING"
HDL_TAP"TRUE";
"B \NAC \NWC"1;
"S \NAC"
BN"13"166;
%"TAP"
"6","(-2850,4500)","2","mstr_standard","I167";
;
CDS_LIB"mstr_standard"
BODY_TYPE"PLUMBING"
HDL_TAP"TRUE";
"B \NAC \NWC"1;
"S \NAC"
BN"14"167;
%"TAP"
"6","(-2850,4550)","2","mstr_standard","I168";
;
CDS_LIB"mstr_standard"
BODY_TYPE"PLUMBING"
HDL_TAP"TRUE";
"B \NAC \NWC"1;
"S \NAC"
BN"15"168;
%"TAP"
"6","(-2850,4600)","2","mstr_standard","I169";
;
CDS_LIB"mstr_standard"
BODY_TYPE"PLUMBING"
HDL_TAP"TRUE";
"B \NAC \NWC"1;
"S \NAC"
BN"16"169;
%"TAP"
"6","(-5575,1250)","0","mstr_standard","I17";
;
CDS_LIB"mstr_standard"
BODY_TYPE"PLUMBING"
HDL_TAP"TRUE";
"B \NAC \NWC"12;
"S \NAC"
BN"4"28;
%"TAP"
"6","(-2850,4650)","2","mstr_standard","I170";
;
CDS_LIB"mstr_standard"
BODY_TYPE"PLUMBING"
HDL_TAP"TRUE";
"B \NAC \NWC"1;
"S \NAC"
BN"17"170;
%"SKX_EXT_B"
"7","(-4175,2550)","0","chpset_lib","I172";
;
CDS_SEC"7"
LOCATION"U5D1"
PART_NUMBER"TBD"
MATERIAL"IC"
PACK_TYPE"BGA1"
CDS_LIB"chpset_lib"
SEC_TYPE"BGA1"
SEC"7"
CDS_LOCATION"U5D1"
ROOM"CPU0";
"DDR4_PAR"
$PN"DV53"119;
"DDR4_ODT<0>"
$PN"DR50"96;
"DDR4_ODT<1>"
$PN"DN48"97;
"DDR4_ODT<2>"
$PN"DT49"98;
"DDR4_ODT<3>"
$PN"DM47"17;
"DDR4_MA<0>"
$PN"DW52"99;
"DDR4_MA<1>"
$PN"DW58"100;
"DDR4_MA<2>"
$PN"DV57"101;
"DDR4_MA<3>"
$PN"DR58"121;
"DDR4_MA<4>"
$PN"DT59"122;
"DDR4_MA<5>"
$PN"DN58"123;
"DDR4_MA<6>"
$PN"DM59"124;
"DDR4_MA<7>"
$PN"DK61"125;
"DDR4_MA<8>"
$PN"DJ60"126;
"DDR4_MA<9>"
$PN"DV59"127;
"DDR4_MA<10>"
$PN"DT55"128;
"DDR4_MA<11>"
$PN"DR60"129;
"DDR4_MA<12>"
$PN"DN60"130;
"DDR4_MA<13>"
$PN"DT51"131;
"DDR4_MA<14>"
$PN"DM51"132;
"DDR4_MA<15>"
$PN"DR52"133;
"DDR4_MA<16>"
$PN"DN52"134;
"DDR4_MA<17>"
$PN"DR48"135;
"DDR4_ECC<0>"
$PN"DY69"24;
"DDR4_ECC<1>"
$PN"EA68"25;
"DDR4_ECC<2>"
$PN"DV65"26;
"DDR4_ECC<3>"
$PN"DY65"27;
"DDR4_ECC<4>"
$PN"DU68"28;
"DDR4_ECC<5>"
$PN"DV69"29;
"DDR4_ECC<6>"
$PN"DU66"30;
"DDR4_ECC<7>"
$PN"EA66"31;
"DDR4_DQS_DP<0>"
$PN"CM81"136;
"DDR4_DQS_DP<1>"
$PN"DB81"137;
"DDR4_DQS_DP<2>"
$PN"EB79"15;
"DDR4_DQS_DP<3>"
$PN"ED73"138;
"DDR4_DQS_DP<4>"
$PN"DT41"139;
"DDR4_DQS_DP<5>"
$PN"EC32"140;
"DDR4_DQS_DP<6>"
$PN"EC26"159;
"DDR4_DQS_DP<7>"
$PN"DJ26"160;
"DDR4_DQS_DP<8>"
$PN"DY67"161;
"DDR4_DQS_DP<9>"
$PN"CP79"162;
"DDR4_DQS_DP<10>"
$PN"DD79"163;
"DDR4_DQS_DP<11>"
$PN"DV79"164;
"DDR4_DQS_DP<12>"
$PN"DY73"165;
"DDR4_DQS_DP<13>"
$PN"DM41"166;
"DDR4_DQS_DP<14>"
$PN"DW32"167;
"DDR4_DQS_DP<15>"
$PN"DW26"168;
"DDR4_DQS_DP<16>"
$PN"DE26"169;
"DDR4_DQS_DP<17>"
$PN"DT67"170;
"DDR4_DQS_DN<0>"
$PN"CL82"141;
"DDR4_DQS_DN<1>"
$PN"DA82"142;
"DDR4_DQS_DN<2>"
$PN"ED79"143;
"DDR4_DQS_DN<3>"
$PN"EF73"144;
"DDR4_DQS_DN<4>"
$PN"DV41"145;
"DDR4_DQS_DN<5>"
$PN"EE32"146;
"DDR4_DQS_DN<6>"
$PN"EE26"147;
"DDR4_DQS_DN<7>"
$PN"DL26"148;
"DDR4_DQS_DN<8>"
$PN"EB67"149;
"DDR4_DQS_DN<9>"
$PN"CN80"150;
"DDR4_DQS_DN<10>"
$PN"DC80"151;
"DDR4_DQS_DN<11>"
$PN"DY79"152;
"DDR4_DQS_DN<12>"
$PN"EB73"153;
"DDR4_DQS_DN<13>"
$PN"DP41"154;
"DDR4_DQS_DN<14>"
$PN"EA32"155;
"DDR4_DQS_DN<15>"
$PN"EA26"156;
"DDR4_DQS_DN<16>"
$PN"DG26"157;
"DDR4_DQS_DN<17>"
$PN"DV67"158;
"DDR4_DQ<0>"
$PN"CM79"32;
"DDR4_DQ<1>"
$PN"CK81"33;
"DDR4_DQ<2>"
$PN"CT81"34;
"DDR4_DQ<3>"
$PN"CR82"35;
"DDR4_DQ<4>"
$PN"CK79"36;
"DDR4_DQ<5>"
$PN"CJ80"22;
"DDR4_DQ<6>"
$PN"CR80"37;
"DDR4_DQ<7>"
$PN"CN82"38;
"DDR4_DQ<8>"
$PN"DB79"39;
"DDR4_DQ<9>"
$PN"CY81"40;
"DDR4_DQ<10>"
$PN"DE80"41;
"DDR4_DQ<11>"
$PN"DF81"50;
"DDR4_DQ<12>"
$PN"CY79"51;
"DDR4_DQ<13>"
$PN"CW80"52;
"DDR4_DQ<14>"
$PN"DC82"53;
"DDR4_DQ<15>"
$PN"DE82"54;
"DDR4_DQ<16>"
$PN"DW80"55;
"DDR4_DQ<17>"
$PN"EC80"56;
"DDR4_DQ<18>"
$PN"DY77"57;
"DDR4_DQ<19>"
$PN"EB77"58;
"DDR4_DQ<20>"
$PN"DY81"59;
"DDR4_DQ<21>"
$PN"EB81"60;
"DDR4_DQ<22>"
$PN"DW78"61;
"DDR4_DQ<23>"
$PN"EC78"62;
"DDR4_DQ<24>"
$PN"ED75"63;
"DDR4_DQ<25>"
$PN"EE74"64;
"DDR4_DQ<26>"
$PN"EB71"65;
"DDR4_DQ<27>"
$PN"ED71"66;
"DDR4_DQ<28>"
$PN"EA74"67;
"DDR4_DQ<29>"
$PN"EB75"68;
"DDR4_DQ<30>"
$PN"EA72"69;
"DDR4_DQ<31>"
$PN"EE72"70;
"DDR4_DQ<32>"
$PN"DU42"71;
"DDR4_DQ<33>"
$PN"DW42"19;
"DDR4_DQ<34>"
$PN"DP39"72;
"DDR4_DQ<35>"
$PN"DT39"18;
"DDR4_DQ<36>"
$PN"DL42"73;
"DDR4_DQ<37>"
$PN"DN42"74;
"DDR4_DQ<38>"
$PN"DN40"20;
"DDR4_DQ<39>"
$PN"DU40"75;
"DDR4_DQ<40>"
$PN"EC34"76;
"DDR4_DQ<41>"
$PN"ED33"14;
"DDR4_DQ<42>"
$PN"EA30"77;
"DDR4_DQ<43>"
$PN"EC30"78;
"DDR4_DQ<44>"
$PN"DY33"79;
"DDR4_DQ<45>"
$PN"EA34"80;
"DDR4_DQ<46>"
$PN"DY31"81;
"DDR4_DQ<47>"
$PN"ED31"82;
"DDR4_DQ<48>"
$PN"EC28"83;
"DDR4_DQ<49>"
$PN"ED27"84;
"DDR4_DQ<50>"
$PN"EA24"85;
"DDR4_DQ<51>"
$PN"EC24"86;
"DDR4_DQ<52>"
$PN"DY27"87;
"DDR4_DQ<53>"
$PN"EA28"16;
"DDR4_DQ<54>"
$PN"DY25"88;
"DDR4_DQ<55>"
$PN"ED25"13;
"DDR4_DQ<56>"
$PN"DF27"89;
"DDR4_DQ<57>"
$PN"DK27"90;
"DDR4_DQ<58>"
$PN"DD25"21;
"DDR4_DQ<59>"
$PN"DJ24"91;
"DDR4_DQ<60>"
$PN"DG28"92;
"DDR4_DQ<61>"
$PN"DJ28"93;
"DDR4_DQ<62>"
$PN"DF25"94;
"DDR4_DQ<63>"
$PN"DK25"95;
"DDR4_CS_N<0>"
$PN"DV51"102;
"DDR4_CS_N<1>"
$PN"DN50"103;
"DDR4_CS_N<2>"
$PN"DR46"104;
"DDR4_CS_N<3>"
$PN"DK47"105;
"DDR4_CS_N<4>"
$PN"DW50"106;
"DDR4_CS_N<5>"
$PN"DM49"107;
"DDR4_CS_N<6>"
$PN"DT45"108;
"DDR4_CS_N<7>"
$PN"DN46"109;
"DDR4_CLK_DP<0>"
$PN"DN54"42;
"DDR4_CLK_DP<1>"
$PN"DT53"43;
"DDR4_CLK_DP<2>"
$PN"DN56"44;
"DDR4_CLK_DP<3>"
$PN"DR56"45;
"DDR4_CLK_DN<0>"
$PN"DM55"46;
"DDR4_CLK_DN<1>"
$PN"DR54"47;
"DDR4_CLK_DN<2>"
$PN"DM57"48;
"DDR4_CLK_DN<3>"
$PN"DT57"49;
"DDR4_CKE<0>"
$PN"DM63"110;
"DDR4_CKE<1>"
$PN"DN64"111;
"DDR4_CKE<2>"
$PN"DL64"112;
"DDR4_CKE<3>"
$PN"DR64"113;
"DDR4_CID<2>"
$PN"DT47"23;
"DDR4_BG<0>"
$PN"DJ62"114;
"DDR4_BG<1>"
$PN"DM61"115;
"DDR4_BA<0>"
$PN"DM53"116;
"DDR4_BA<1>"
$PN"DV55"117;
"DDR4_ALERT_N"
$PN"DT61"118;
"DDR4_ACT_N"
$PN"DR62"120;
%"TAP"
"6","(-5575,1300)","0","mstr_standard","I18";
;
CDS_LIB"mstr_standard"
BODY_TYPE"PLUMBING"
HDL_TAP"TRUE";
"B \NAC \NWC"12;
"S \NAC"
BN"5"29;
%"TAP"
"6","(-5575,1350)","0","mstr_standard","I19";
;
CDS_LIB"mstr_standard"
BODY_TYPE"PLUMBING"
HDL_TAP"TRUE";
"B \NAC \NWC"12;
"S \NAC"
BN"6"30;
%"TAP"
"6","(-5575,1400)","0","mstr_standard","I20";
;
CDS_LIB"mstr_standard"
BODY_TYPE"PLUMBING"
HDL_TAP"TRUE";
"B \NAC \NWC"12;
"S \NAC"
BN"7"31;
%"TAP"
"6","(-5575,1550)","0","mstr_standard","I21";
;
CDS_LIB"mstr_standard"
BODY_TYPE"PLUMBING"
HDL_TAP"TRUE";
"B \NAC \NWC"9;
"S \NAC"
BN"1"33;
%"TAP"
"6","(-5575,1500)","0","mstr_standard","I22";
;
CDS_LIB"mstr_standard"
BODY_TYPE"PLUMBING"
HDL_TAP"TRUE";
"B \NAC \NWC"9;
"S \NAC"
BN"0"32;
%"TAP"
"6","(-5575,1600)","0","mstr_standard","I23";
;
CDS_LIB"mstr_standard"
BODY_TYPE"PLUMBING"
HDL_TAP"TRUE";
"B \NAC \NWC"9;
"S \NAC"
BN"2"34;
%"TAP"
"6","(-5575,1650)","0","mstr_standard","I24";
;
CDS_LIB"mstr_standard"
BODY_TYPE"PLUMBING"
HDL_TAP"TRUE";
"B \NAC \NWC"9;
"S \NAC"
BN"3"35;
%"TAP"
"6","(-5575,1700)","0","mstr_standard","I25";
;
CDS_LIB"mstr_standard"
BODY_TYPE"PLUMBING"
HDL_TAP"TRUE";
"B \NAC \NWC"9;
"S \NAC"
BN"4"36;
%"TAP"
"6","(-5575,1750)","0","mstr_standard","I26";
;
CDS_LIB"mstr_standard"
BODY_TYPE"PLUMBING"
HDL_TAP"TRUE";
"B \NAC \NWC"9;
"S \NAC"
BN"5"22;
%"TAP"
"6","(-5575,1800)","0","mstr_standard","I27";
;
CDS_LIB"mstr_standard"
BODY_TYPE"PLUMBING"
HDL_TAP"TRUE";
"B \NAC \NWC"9;
"S \NAC"
BN"6"37;
%"TAP"
"6","(-5575,1900)","0","mstr_standard","I28";
;
CDS_LIB"mstr_standard"
BODY_TYPE"PLUMBING"
HDL_TAP"TRUE";
"B \NAC \NWC"9;
"S \NAC"
BN"8"39;
%"TAP"
"6","(-5575,1850)","0","mstr_standard","I29";
;
CDS_LIB"mstr_standard"
BODY_TYPE"PLUMBING"
HDL_TAP"TRUE";
"B \NAC \NWC"9;
"S \NAC"
BN"7"38;
%"TAP"
"6","(-5575,1950)","0","mstr_standard","I30";
;
CDS_LIB"mstr_standard"
BODY_TYPE"PLUMBING"
HDL_TAP"TRUE";
"B \NAC \NWC"9;
"S \NAC"
BN"9"40;
%"TAP"
"6","(-5575,2000)","0","mstr_standard","I32";
;
CDS_LIB"mstr_standard"
BODY_TYPE"PLUMBING"
HDL_TAP"TRUE";
"B \NAC \NWC"9;
"S \NAC"
BN"10"41;
%"TAP"
"6","(-5575,2050)","0","mstr_standard","I33";
;
CDS_LIB"mstr_standard"
BODY_TYPE"PLUMBING"
HDL_TAP"TRUE";
"B \NAC \NWC"9;
"S \NAC"
BN"11"50;
%"TAP"
"6","(-5575,2100)","0","mstr_standard","I34";
;
CDS_LIB"mstr_standard"
BODY_TYPE"PLUMBING"
HDL_TAP"TRUE";
"B \NAC \NWC"9;
"S \NAC"
BN"12"51;
%"TAP"
"6","(-5575,2150)","0","mstr_standard","I35";
;
CDS_LIB"mstr_standard"
BODY_TYPE"PLUMBING"
HDL_TAP"TRUE";
"B \NAC \NWC"9;
"S \NAC"
BN"13"52;
%"TAP"
"6","(-5575,2200)","0","mstr_standard","I36";
;
CDS_LIB"mstr_standard"
BODY_TYPE"PLUMBING"
HDL_TAP"TRUE";
"B \NAC \NWC"9;
"S \NAC"
BN"14"53;
%"TAP"
"6","(-5575,2250)","0","mstr_standard","I37";
;
CDS_LIB"mstr_standard"
BODY_TYPE"PLUMBING"
HDL_TAP"TRUE";
"B \NAC \NWC"9;
"S \NAC"
BN"15"54;
%"TAP"
"6","(-5575,2300)","0","mstr_standard","I38";
;
CDS_LIB"mstr_standard"
BODY_TYPE"PLUMBING"
HDL_TAP"TRUE";
"B \NAC \NWC"9;
"S \NAC"
BN"16"55;
%"TAP"
"6","(-5575,2350)","0","mstr_standard","I39";
;
CDS_LIB"mstr_standard"
BODY_TYPE"PLUMBING"
HDL_TAP"TRUE";
"B \NAC \NWC"9;
"S \NAC"
BN"17"56;
%"TAP"
"6","(-5575,2400)","0","mstr_standard","I40";
;
CDS_LIB"mstr_standard"
BODY_TYPE"PLUMBING"
HDL_TAP"TRUE";
"B \NAC \NWC"9;
"S \NAC"
BN"18"57;
%"TAP"
"6","(-5575,2450)","0","mstr_standard","I41";
;
CDS_LIB"mstr_standard"
BODY_TYPE"PLUMBING"
HDL_TAP"TRUE";
"B \NAC \NWC"9;
"S \NAC"
BN"19"58;
%"TAP"
"6","(-5575,2500)","0","mstr_standard","I42";
;
CDS_LIB"mstr_standard"
BODY_TYPE"PLUMBING"
HDL_TAP"TRUE";
"B \NAC \NWC"9;
"S \NAC"
BN"20"59;
%"TAP"
"6","(-5575,2550)","0","mstr_standard","I43";
;
CDS_LIB"mstr_standard"
BODY_TYPE"PLUMBING"
HDL_TAP"TRUE";
"B \NAC \NWC"9;
"S \NAC"
BN"21"60;
%"TAP"
"6","(-5575,2600)","0","mstr_standard","I44";
;
CDS_LIB"mstr_standard"
BODY_TYPE"PLUMBING"
HDL_TAP"TRUE";
"B \NAC \NWC"9;
"S \NAC"
BN"22"61;
%"TAP"
"6","(-5575,2650)","0","mstr_standard","I45";
;
CDS_LIB"mstr_standard"
BODY_TYPE"PLUMBING"
HDL_TAP"TRUE";
"B \NAC \NWC"9;
"S \NAC"
BN"23"62;
%"TAP"
"6","(-5575,2700)","0","mstr_standard","I46";
;
CDS_LIB"mstr_standard"
BODY_TYPE"PLUMBING"
HDL_TAP"TRUE";
"B \NAC \NWC"9;
"S \NAC"
BN"24"63;
%"TAP"
"6","(-5575,2800)","0","mstr_standard","I47";
;
CDS_LIB"mstr_standard"
BODY_TYPE"PLUMBING"
HDL_TAP"TRUE";
"B \NAC \NWC"9;
"S \NAC"
BN"26"65;
%"TAP"
"6","(-5575,2750)","0","mstr_standard","I48";
;
CDS_LIB"mstr_standard"
BODY_TYPE"PLUMBING"
HDL_TAP"TRUE";
"B \NAC \NWC"9;
"S \NAC"
BN"25"64;
%"TAP"
"6","(-5575,2850)","0","mstr_standard","I49";
;
CDS_LIB"mstr_standard"
BODY_TYPE"PLUMBING"
HDL_TAP"TRUE";
"B \NAC \NWC"9;
"S \NAC"
BN"27"66;
%"TAP"
"6","(-5575,600)","0","mstr_standard","I5";
;
CDS_LIB"mstr_standard"
BODY_TYPE"PLUMBING"
HDL_TAP"TRUE";
"B \NAC \NWC"10;
"S \NAC"
BN"0"46;
%"TAP"
"6","(-5575,2900)","0","mstr_standard","I50";
;
CDS_LIB"mstr_standard"
BODY_TYPE"PLUMBING"
HDL_TAP"TRUE";
"B \NAC \NWC"9;
"S \NAC"
BN"28"67;
%"TAP"
"6","(-5575,2950)","0","mstr_standard","I51";
;
CDS_LIB"mstr_standard"
BODY_TYPE"PLUMBING"
HDL_TAP"TRUE";
"B \NAC \NWC"9;
"S \NAC"
BN"29"68;
%"TAP"
"6","(-5575,3050)","0","mstr_standard","I52";
;
CDS_LIB"mstr_standard"
BODY_TYPE"PLUMBING"
HDL_TAP"TRUE";
"B \NAC \NWC"9;
"S \NAC"
BN"31"70;
%"TAP"
"6","(-5575,3000)","0","mstr_standard","I53";
;
CDS_LIB"mstr_standard"
BODY_TYPE"PLUMBING"
HDL_TAP"TRUE";
"B \NAC \NWC"9;
"S \NAC"
BN"30"69;
%"TAP"
"6","(-5575,3100)","0","mstr_standard","I54";
;
CDS_LIB"mstr_standard"
BODY_TYPE"PLUMBING"
HDL_TAP"TRUE";
"B \NAC \NWC"9;
"S \NAC"
BN"32"71;
%"TAP"
"6","(-5575,3150)","0","mstr_standard","I55";
;
CDS_LIB"mstr_standard"
BODY_TYPE"PLUMBING"
HDL_TAP"TRUE";
"B \NAC \NWC"9;
"S \NAC"
BN"33"19;
%"TAP"
"6","(-5575,3200)","0","mstr_standard","I56";
;
CDS_LIB"mstr_standard"
BODY_TYPE"PLUMBING"
HDL_TAP"TRUE";
"B \NAC \NWC"9;
"S \NAC"
BN"34"72;
%"TAP"
"6","(-5575,3250)","0","mstr_standard","I57";
;
CDS_LIB"mstr_standard"
BODY_TYPE"PLUMBING"
HDL_TAP"TRUE";
"B \NAC \NWC"9;
"S \NAC"
BN"35"18;
%"TAP"
"6","(-5575,3300)","0","mstr_standard","I58";
;
CDS_LIB"mstr_standard"
BODY_TYPE"PLUMBING"
HDL_TAP"TRUE";
"B \NAC \NWC"9;
"S \NAC"
BN"36"73;
%"TAP"
"6","(-5575,3350)","0","mstr_standard","I59";
;
CDS_LIB"mstr_standard"
BODY_TYPE"PLUMBING"
HDL_TAP"TRUE";
"B \NAC \NWC"9;
"S \NAC"
BN"37"74;
%"TAP"
"6","(-5575,650)","0","mstr_standard","I6";
;
CDS_LIB"mstr_standard"
BODY_TYPE"PLUMBING"
HDL_TAP"TRUE";
"B \NAC \NWC"10;
"S \NAC"
BN"1"47;
%"TAP"
"6","(-5575,3400)","0","mstr_standard","I60";
;
CDS_LIB"mstr_standard"
BODY_TYPE"PLUMBING"
HDL_TAP"TRUE";
"B \NAC \NWC"9;
"S \NAC"
BN"38"20;
%"TAP"
"6","(-5575,3450)","0","mstr_standard","I61";
;
CDS_LIB"mstr_standard"
BODY_TYPE"PLUMBING"
HDL_TAP"TRUE";
"B \NAC \NWC"9;
"S \NAC"
BN"39"75;
%"TAP"
"6","(-5575,3500)","0","mstr_standard","I62";
;
CDS_LIB"mstr_standard"
BODY_TYPE"PLUMBING"
HDL_TAP"TRUE";
"B \NAC \NWC"9;
"S \NAC"
BN"40"76;
%"TAP"
"6","(-5575,3550)","0","mstr_standard","I63";
;
CDS_LIB"mstr_standard"
BODY_TYPE"PLUMBING"
HDL_TAP"TRUE";
"B \NAC \NWC"9;
"S \NAC"
BN"41"14;
%"TAP"
"6","(-5575,3600)","0","mstr_standard","I64";
;
CDS_LIB"mstr_standard"
BODY_TYPE"PLUMBING"
HDL_TAP"TRUE";
"B \NAC \NWC"9;
"S \NAC"
BN"42"77;
%"TAP"
"6","(-5575,3650)","0","mstr_standard","I65";
;
CDS_LIB"mstr_standard"
BODY_TYPE"PLUMBING"
HDL_TAP"TRUE";
"B \NAC \NWC"9;
"S \NAC"
BN"43"78;
%"TAP"
"6","(-5575,3700)","0","mstr_standard","I66";
;
CDS_LIB"mstr_standard"
BODY_TYPE"PLUMBING"
HDL_TAP"TRUE";
"B \NAC \NWC"9;
"S \NAC"
BN"44"79;
%"TAP"
"6","(-5575,3750)","0","mstr_standard","I67";
;
CDS_LIB"mstr_standard"
BODY_TYPE"PLUMBING"
HDL_TAP"TRUE";
"B \NAC \NWC"9;
"S \NAC"
BN"45"80;
%"TAP"
"6","(-5575,3800)","0","mstr_standard","I68";
;
CDS_LIB"mstr_standard"
BODY_TYPE"PLUMBING"
HDL_TAP"TRUE";
"B \NAC \NWC"9;
"S \NAC"
BN"46"81;
%"TAP"
"6","(-5575,3850)","0","mstr_standard","I69";
;
CDS_LIB"mstr_standard"
BODY_TYPE"PLUMBING"
HDL_TAP"TRUE";
"B \NAC \NWC"9;
"S \NAC"
BN"47"82;
%"TAP"
"6","(-5575,750)","0","mstr_standard","I7";
;
CDS_LIB"mstr_standard"
BODY_TYPE"PLUMBING"
HDL_TAP"TRUE";
"B \NAC \NWC"10;
"S \NAC"
BN"3"49;
%"TAP"
"6","(-5575,3900)","0","mstr_standard","I70";
;
CDS_LIB"mstr_standard"
BODY_TYPE"PLUMBING"
HDL_TAP"TRUE";
"B \NAC \NWC"9;
"S \NAC"
BN"48"83;
%"TAP"
"6","(-5575,3950)","0","mstr_standard","I71";
;
CDS_LIB"mstr_standard"
BODY_TYPE"PLUMBING"
HDL_TAP"TRUE";
"B \NAC \NWC"9;
"S \NAC"
BN"49"84;
%"TAP"
"6","(-5575,4000)","0","mstr_standard","I72";
;
CDS_LIB"mstr_standard"
BODY_TYPE"PLUMBING"
HDL_TAP"TRUE";
"B \NAC \NWC"9;
"S \NAC"
BN"50"85;
%"TAP"
"6","(-5575,4050)","0","mstr_standard","I74";
;
CDS_LIB"mstr_standard"
BODY_TYPE"PLUMBING"
HDL_TAP"TRUE";
"B \NAC \NWC"9;
"S \NAC"
BN"51"86;
%"TAP"
"6","(-5575,4100)","0","mstr_standard","I75";
;
CDS_LIB"mstr_standard"
BODY_TYPE"PLUMBING"
HDL_TAP"TRUE";
"B \NAC \NWC"9;
"S \NAC"
BN"52"87;
%"TAP"
"6","(-5575,4150)","0","mstr_standard","I76";
;
CDS_LIB"mstr_standard"
BODY_TYPE"PLUMBING"
HDL_TAP"TRUE";
"B \NAC \NWC"9;
"S \NAC"
BN"53"16;
%"TAP"
"6","(-5575,4200)","0","mstr_standard","I77";
;
CDS_LIB"mstr_standard"
BODY_TYPE"PLUMBING"
HDL_TAP"TRUE";
"B \NAC \NWC"9;
"S \NAC"
BN"54"88;
%"TAP"
"6","(-5575,4250)","0","mstr_standard","I78";
;
CDS_LIB"mstr_standard"
BODY_TYPE"PLUMBING"
HDL_TAP"TRUE";
"B \NAC \NWC"9;
"S \NAC"
BN"55"13;
%"TAP"
"6","(-5575,4300)","0","mstr_standard","I79";
;
CDS_LIB"mstr_standard"
BODY_TYPE"PLUMBING"
HDL_TAP"TRUE";
"B \NAC \NWC"9;
"S \NAC"
BN"56"89;
%"TAP"
"6","(-5575,700)","0","mstr_standard","I8";
;
CDS_LIB"mstr_standard"
BODY_TYPE"PLUMBING"
HDL_TAP"TRUE";
"B \NAC \NWC"10;
"S \NAC"
BN"2"48;
%"TAP"
"6","(-5575,4350)","0","mstr_standard","I80";
;
CDS_LIB"mstr_standard"
BODY_TYPE"PLUMBING"
HDL_TAP"TRUE";
"B \NAC \NWC"9;
"S \NAC"
BN"57"90;
%"TAP"
"6","(-5575,4400)","0","mstr_standard","I81";
;
CDS_LIB"mstr_standard"
BODY_TYPE"PLUMBING"
HDL_TAP"TRUE";
"B \NAC \NWC"9;
"S \NAC"
BN"58"21;
%"TAP"
"6","(-5575,4450)","0","mstr_standard","I82";
;
CDS_LIB"mstr_standard"
BODY_TYPE"PLUMBING"
HDL_TAP"TRUE";
"B \NAC \NWC"9;
"S \NAC"
BN"59"91;
%"TAP"
"6","(-5575,4500)","0","mstr_standard","I83";
;
CDS_LIB"mstr_standard"
BODY_TYPE"PLUMBING"
HDL_TAP"TRUE";
"B \NAC \NWC"9;
"S \NAC"
BN"60"92;
%"TAP"
"6","(-5575,4550)","0","mstr_standard","I84";
;
CDS_LIB"mstr_standard"
BODY_TYPE"PLUMBING"
HDL_TAP"TRUE";
"B \NAC \NWC"9;
"S \NAC"
BN"61"93;
%"TAP"
"6","(-5575,4600)","0","mstr_standard","I85";
;
CDS_LIB"mstr_standard"
BODY_TYPE"PLUMBING"
HDL_TAP"TRUE";
"B \NAC \NWC"9;
"S \NAC"
BN"62"94;
%"TAP"
"6","(-5575,4650)","0","mstr_standard","I86";
;
CDS_LIB"mstr_standard"
BODY_TYPE"PLUMBING"
HDL_TAP"TRUE";
"B \NAC \NWC"9;
"S \NAC"
BN"63"95;
%"TAP"
"6","(-2850,800)","2","mstr_standard","I87";
;
CDS_LIB"mstr_standard"
BODY_TYPE"PLUMBING"
HDL_TAP"TRUE";
"B \NAC \NWC"5;
"S \NAC"
BN"0"114;
%"TAP"
"6","(-2850,750)","2","mstr_standard","I88";
;
CDS_LIB"mstr_standard"
BODY_TYPE"PLUMBING"
HDL_TAP"TRUE";
"B \NAC \NWC"4;
"S \NAC"
BN"1"117;
%"TAP"
"6","(-2850,700)","2","mstr_standard","I89";
;
CDS_LIB"mstr_standard"
BODY_TYPE"PLUMBING"
HDL_TAP"TRUE";
"B \NAC \NWC"4;
"S \NAC"
BN"0"116;
%"TAP"
"6","(-5575,800)","0","mstr_standard","I9";
;
CDS_LIB"mstr_standard"
BODY_TYPE"PLUMBING"
HDL_TAP"TRUE";
"B \NAC \NWC"11;
"S \NAC"
BN"0"42;
%"TAP"
"6","(-2850,850)","2","mstr_standard","I90";
;
CDS_LIB"mstr_standard"
BODY_TYPE"PLUMBING"
HDL_TAP"TRUE";
"B \NAC \NWC"5;
"S \NAC"
BN"1"115;
%"TAP"
"6","(-2850,1000)","2","mstr_standard","I91";
;
CDS_LIB"mstr_standard"
BODY_TYPE"PLUMBING"
HDL_TAP"TRUE";
"B \NAC \NWC"7;
"S \NAC"
BN"1"103;
%"TAP"
"6","(-2850,950)","2","mstr_standard","I92";
;
CDS_LIB"mstr_standard"
BODY_TYPE"PLUMBING"
HDL_TAP"TRUE";
"B \NAC \NWC"7;
"S \NAC"
BN"0"102;
%"TAP"
"6","(-2850,1050)","2","mstr_standard","I93";
;
CDS_LIB"mstr_standard"
BODY_TYPE"PLUMBING"
HDL_TAP"TRUE";
"B \NAC \NWC"7;
"S \NAC"
BN"2"104;
%"TAP"
"6","(-2850,1200)","2","mstr_standard","I94";
;
CDS_LIB"mstr_standard"
BODY_TYPE"PLUMBING"
HDL_TAP"TRUE";
"B \NAC \NWC"7;
"S \NAC"
BN"5"107;
%"TAP"
"6","(-2850,1100)","2","mstr_standard","I95";
;
CDS_LIB"mstr_standard"
BODY_TYPE"PLUMBING"
HDL_TAP"TRUE";
"B \NAC \NWC"7;
"S \NAC"
BN"3"105;
%"TAP"
"6","(-2850,1150)","2","mstr_standard","I96";
;
CDS_LIB"mstr_standard"
BODY_TYPE"PLUMBING"
HDL_TAP"TRUE";
"B \NAC \NWC"7;
"S \NAC"
BN"4"106;
%"TAP"
"6","(-2850,1250)","2","mstr_standard","I97";
;
CDS_LIB"mstr_standard"
BODY_TYPE"PLUMBING"
HDL_TAP"TRUE";
"B \NAC \NWC"7;
"S \NAC"
BN"6"108;
%"TAP"
"6","(-2850,1300)","2","mstr_standard","I98";
;
CDS_LIB"mstr_standard"
BODY_TYPE"PLUMBING"
HDL_TAP"TRUE";
"B \NAC \NWC"7;
"S \NAC"
BN"7"109;
%"TAP"
"6","(-2850,1450)","2","mstr_standard","I99";
;
CDS_LIB"mstr_standard"
BODY_TYPE"PLUMBING"
HDL_TAP"TRUE";
"B \NAC \NWC"8;
"S \NAC"
BN"1"97;
END.
